# S9S_MB_2U (Grand Teton) — schematic netlist excerpt (pin names and nets, part order shuffled) for the footprints in the layout excerpt that follows; sources: Cadence DE-HDL packaged netlist, KiCad conversion of 03242023_DA0F0TMBIJ0_F0T_Motherboard_J_brd_V01_OCP.brd

PC601  Q_CAP  2.2UF 10V 10% X6S  pkg C0402  page 271 : A = PVCCFA_EHV_FIVRA_CPU0_VDD2 ; B = GND
R4155  Q_RES  4.7K 5% CHIP  pkg 0402LF  page 146 : A = P3V3_AUX ; B = PRSNT_CABLE_GPU_A1

(kicad_pcb
	(version 20260206)
	(generator "pcbnew")
	(generator_version "10.0")
	(general
		(thickness 1.6)
		(legacy_teardrops no)
	)
	(paper "A4")
	(title_block
		(title "03242023_DA0F0TMBIJ0_F0T_Motherboard_J_brd_V01_OCP.brd")
		(comment 1 "Grand Teton / footprints 1330-1331 of 6105")
	)
	(layers
		(0 "F.Cu" signal "TOP")
		(4 "In1.Cu" signal "GND")
		(6 "In2.Cu" signal "IN1")
		(8 "In3.Cu" signal "GND1")
		(10 "In4.Cu" signal "IN2")
		(12 "In5.Cu" signal "GND2")
		(14 "In6.Cu" signal "IN3")
		(16 "In7.Cu" signal "GND3")
		(18 "In8.Cu" signal "VCC")
		(20 "In9.Cu" signal "VCC1")
		(22 "In10.Cu" signal "GND4")
		(24 "In11.Cu" signal "IN4")
		(26 "In12.Cu" signal "GND5")
		(28 "In13.Cu" signal "IN5")
		(30 "In14.Cu" signal "GND6")
		(32 "In15.Cu" signal "IN6")
		(34 "In16.Cu" signal "GND7")
		(2 "B.Cu" signal "BOTTOM")
		(9 "F.Adhes" user "F.Adhesive")
		(11 "B.Adhes" user "B.Adhesive")
		(13 "F.Paste" user "Package Geometry/Pastemask Top")
		(15 "B.Paste" user "Package Geometry/Pastemask Bottom")
		(5 "F.SilkS" user "Ref Des/Silkscreen Top")
		(7 "B.SilkS" user "Ref Des/Silkscreen Bottom")
		(1 "F.Mask" user "Board Geometry/Soldermask Top")
		(3 "B.Mask" user "Board Geometry/Soldermask Bottom")
		(17 "Dwgs.User" user "User.Drawings")
		(19 "Cmts.User" user "User.Comments")
		(21 "Eco1.User" user "User.Eco1")
		(23 "Eco2.User" user "User.Eco2")
		(25 "Edge.Cuts" user "Board Geometry/Outline")
		(27 "Margin" user)
		(31 "F.CrtYd" user "Package Geometry/Place Bound Top")
		(29 "B.CrtYd" user "Package Geometry/Place Bound Bottom")
		(35 "F.Fab" user "Ref Des/Assembly Top")
		(33 "B.Fab" user "Ref Des/Assembly Bottom")
	)
	(footprint ""
		(layer "F.Cu")
		(at 294.899588 -365.251746 90)
		(property "Reference" "PC601"
			(at 0 0 90)
			(layer "F.SilkS")
			(hide yes)
			(effects
				(font
					(size 1.27 1.27)
				)
			)
		)
		(property "Value" ""
			(at 0 0 90)
			(layer "F.Fab")
			(effects
				(font
					(size 1.27 1.27)
				)
			)
		)
		(duplicate_pad_numbers_are_jumpers no)
		(fp_line
			(start 0.7874 -0.4064)
			(end 0.7874 0.4064)
			(stroke
				(width 0.1524)
				(type default)
			)
			(layer "F.SilkS")
		)
		(fp_line
			(start -0.7874 -0.4064)
			(end 0.7874 -0.4064)
			(stroke
				(width 0.1524)
				(type default)
			)
			(layer "F.SilkS")
		)
		(fp_line
			(start 0.7874 0.4064)
			(end -0.7874 0.4064)
			(stroke
				(width 0.1524)
				(type default)
			)
			(layer "F.SilkS")
		)
		(fp_line
			(start -0.7874 0.4064)
			(end -0.7874 -0.4064)
			(stroke
				(width 0.1524)
				(type default)
			)
			(layer "F.SilkS")
		)
		(fp_line
			(start -0.12065 -0.305054)
			(end -0.12065 -0.2794)
			(stroke
				(width 0.1)
				(type default)
			)
			(layer "F.Fab")
		)
		(fp_line
			(start -0.67945 -0.305054)
			(end -0.12065 -0.305054)
			(stroke
				(width 0.1)
				(type default)
			)
			(layer "F.Fab")
		)
		(fp_line
			(start 0.67945 -0.3048)
			(end 0.67945 0.3048)
			(stroke
				(width 0.1)
				(type default)
			)
			(layer "F.Fab")
		)
		(fp_line
			(start 0.12065 -0.3048)
			(end 0.67945 -0.3048)
			(stroke
				(width 0.1)
				(type default)
			)
			(layer "F.Fab")
		)
		(fp_line
			(start 0.12065 -0.2794)
			(end 0.12065 -0.3048)
			(stroke
				(width 0.1)
				(type default)
			)
			(layer "F.Fab")
		)
		(fp_line
			(start -0.12065 -0.2794)
			(end 0.12065 -0.2794)
			(stroke
				(width 0.1)
				(type default)
			)
			(layer "F.Fab")
		)
		(fp_line
			(start 0.120396 0.2794)
			(end -0.12065 0.2794)
			(stroke
				(width 0.1)
				(type default)
			)
			(layer "F.Fab")
		)
		(fp_line
			(start -0.12065 0.2794)
			(end -0.12065 0.3048)
			(stroke
				(width 0.1)
				(type default)
			)
			(layer "F.Fab")
		)
		(fp_line
			(start 0.67945 0.3048)
			(end 0.120396 0.3048)
			(stroke
				(width 0.1)
				(type default)
			)
			(layer "F.Fab")
		)
		(fp_line
			(start 0.120396 0.3048)
			(end 0.120396 0.2794)
			(stroke
				(width 0.1)
				(type default)
			)
			(layer "F.Fab")
		)
		(fp_line
			(start -0.12065 0.3048)
			(end -0.67945 0.3048)
			(stroke
				(width 0.1)
				(type default)
			)
			(layer "F.Fab")
		)
		(fp_line
			(start -0.67945 0.3048)
			(end -0.67945 -0.305054)
			(stroke
				(width 0.1)
				(type default)
			)
			(layer "F.Fab")
		)
		(pad "1" smd circle
			(at -0.40005 0 90)
			(size 0 0)
			(layers "F.Cu" "F.Mask" "F.Paste")
			(net "PVCCFA_EHV_FIVRA_CPU0_VDD2")
		)
		(pad "2" smd circle
			(at 0.40005 0 90)
			(size 0 0)
			(layers "F.Cu" "F.Mask" "F.Paste")
			(net "GND")
		)
	)
	(footprint ""
		(layer "F.Cu")
		(at 295.548304 -426.478446 -90)
		(property "Reference" "R4155"
			(at 0 0 270)
			(layer "F.SilkS")
			(hide yes)
			(effects
				(font
					(size 1.27 1.27)
				)
			)
		)
		(property "Value" ""
			(at 0 0 270)
			(layer "F.Fab")
			(effects
				(font
					(size 1.27 1.27)
				)
			)
		)
		(duplicate_pad_numbers_are_jumpers no)
		(fp_line
			(start -0.7874 0.4064)
			(end -0.7874 -0.4064)
			(stroke
				(width 0.1524)
				(type default)
			)
			(layer "F.SilkS")
		)
		(fp_line
			(start 0.7874 0.4064)
			(end -0.7874 0.4064)
			(stroke
				(width 0.1524)
				(type default)
			)
			(layer "F.SilkS")
		)
		(fp_line
			(start -0.7874 -0.4064)
			(end 0.7874 -0.4064)
			(stroke
				(width 0.1524)
				(type default)
			)
			(layer "F.SilkS")
		)
		(fp_line
			(start 0.7874 -0.4064)
			(end 0.7874 0.4064)
			(stroke
				(width 0.1524)
				(type default)
			)
			(layer "F.SilkS")
		)
		(fp_line
			(start -0.67945 0.3048)
			(end -0.67945 -0.305054)
			(stroke
				(width 0.1)
				(type default)
			)
			(layer "F.Fab")
		)
		(fp_line
			(start -0.12065 0.3048)
			(end -0.67945 0.3048)
			(stroke
				(width 0.1)
				(type default)
			)
			(layer "F.Fab")
		)
		(fp_line
			(start 0.120396 0.3048)
			(end 0.120396 0.2794)
			(stroke
				(width 0.1)
				(type default)
			)
			(layer "F.Fab")
		)
		(fp_line
			(start 0.67945 0.3048)
			(end 0.120396 0.3048)
			(stroke
				(width 0.1)
				(type default)
			)
			(layer "F.Fab")
		)
		(fp_line
			(start -0.12065 0.2794)
			(end -0.12065 0.3048)
			(stroke
				(width 0.1)
				(type default)
			)
			(layer "F.Fab")
		)
		(fp_line
			(start 0.120396 0.2794)
			(end -0.12065 0.2794)
			(stroke
				(width 0.1)
				(type default)
			)
			(layer "F.Fab")
		)
		(fp_line
			(start -0.12065 -0.2794)
			(end 0.12065 -0.2794)
			(stroke
				(width 0.1)
				(type default)
			)
			(layer "F.Fab")
		)
		(fp_line
			(start 0.12065 -0.2794)
			(end 0.12065 -0.3048)
			(stroke
				(width 0.1)
				(type default)
			)
			(layer "F.Fab")
		)
		(fp_line
			(start 0.12065 -0.3048)
			(end 0.67945 -0.3048)
			(stroke
				(width 0.1)
				(type default)
			)
			(layer "F.Fab")
		)
		(fp_line
			(start 0.67945 -0.3048)
			(end 0.67945 0.3048)
			(stroke
				(width 0.1)
				(type default)
			)
			(layer "F.Fab")
		)
		(fp_line
			(start -0.67945 -0.305054)
			(end -0.12065 -0.305054)
			(stroke
				(width 0.1)
				(type default)
			)
			(layer "F.Fab")
		)
		(fp_line
			(start -0.12065 -0.305054)
			(end -0.12065 -0.2794)
			(stroke
				(width 0.1)
				(type default)
			)
			(layer "F.Fab")
		)
		(pad "1" smd circle
			(at -0.40005 0 270)
			(size 0 0)
			(layers "F.Cu" "F.Mask" "F.Paste")
			(net "P3V3_AUX")
		)
		(pad "2" smd circle
			(at 0.40005 0 270)
			(size 0 0)
			(layers "F.Cu" "F.Mask" "F.Paste")
			(net "PRSNT_CABLE_GPU_A1")
		)
	)
)
